# SEB_8Layer_Stackup.xlsx — Wiwynn (pcb-stackup)
|  |  |  |  |  |  | Version |  |  |  |  |  |  |  |  |  |  |  |  |  |  |
| Board Number: |  | 12004-SA |  |  |  | 01 |  |  |  |  |  |  |  |  |  |  |  |  |  |  |
| Project name: |  | Honey Badger |  |  |  |  |  |  |  |  |  |  |  |  |  |  |  |  |  |  |
| Model Name: |  | SAS EXPANDER BOARD |  |  |  |  |  |  |  |  |  |  |  |  |  |  |  |  |  |  |
| Layer Count: |  | 8 Layer |  |  |  |  |  |  |  |  |  |  |  |  |  |  |  |  |  |  |
| Date: |  | 41046 |  |  |  |  |  |  |  |  |  |  |  |  |  |  |  |  |  |  |
| Material: |  | TU722 +RTF |  |  |  |  |  |  |  | Single Ended Type(mil) |  |  |  |  | Differential Type(mil) |  |  |  |  |  |
| Green factor/Surface treatment/Tg: |  | Lead-Free/ OSP/Tg>170 |  |  |  |  |  |  | Imp | 50 |  |  |  | Imp | 100 |  |  |  |  |  |
| Customer: |  |  |  |  |  |  |  |  | Variation | Inner/Outer+/-5ohm |  |  |  | Variation | Inner/Outer+/-10% |  |  |  |  |  |
| EE engineer |  |  |  |  |  |  |  |  | Bus | Misc. |  |  |  | Bus | SAS/SATA |  |  |  |  |  |
| SI Engineer |  |  |  |  |  |  |  |  |  |  |  |  |  |  |  |  |  |  |  |  |
|  |  |  |  |  |  |  |  |  | Type | SE |  |  |  | Type | DP |  |  |  |  |  |
| Layer |  |  | Thickness |  | Glass/Copper Style | Er |  | Df(1G) | Layers | 1,3,6,8 |  |  |  | Layers | 1,3,6,8 |  |  |  |  |  |
|  |  | Cu oz | Wiwynn |  |  | Wiwynn |  |  |  | Wiwynn |  |  |  |  | Wiwynn |  |  |  |  |  |
|  | Mask |  | 0.5 |  |  | 3.8 |  |  |  | Width | Imp | Width | Imp |  | Width | Space | Imp | Width | Space | Imp |
| Top | Signal | 0.5 oz+plating | 1.9 |  |  |  |  |  | S1 | 4 |  |  |  | S1 | 4 | 9 |  |  |  |  |
|  | Prepreg |  | 2.7 |  |  | 3.5 |  |  |  |  |  |  |  |  |  |  |  |  |  |  |
| L2 | GND | 2 oz | 2.6 |  |  |  |  |  | P2 |  |  |  |  | P2 |  |  |  |  |  |  |
|  | Core |  | 4 |  |  | 3.7 |  |  |  |  |  |  |  |  |  |  |  |  |  |  |
| L3 | Signal | 1 oz | 1.3 |  |  |  |  |  | S3 | 4.5 |  |  |  | S3 |  |  |  |  |  |  |
|  | Prepreg |  | 12.5 |  |  | 4.4000000000000004 |  |  |  |  |  |  |  |  |  |  |  |  |  |  |
| L4 | PWR | 2 oz | 2.6 |  |  |  |  |  | P4 |  |  |  |  | P4 |  |  |  |  |  |  |
|  | Core |  | 4 |  |  | 4.0999999999999996 |  |  |  |  |  |  |  |  |  |  |  |  |  |  |
| L5 | PWR | 2 oz | 2.6 | 0 |  |  |  |  | S5 |  |  |  |  | S5 |  |  |  |  |  |  |
|  | Prepreg |  | 12.5 | 0 |  | 4.4000000000000004 | 0 |  |  |  |  |  |  |  |  |  |  |  |  |  |
| L6 | Signal | 1 oz | 1.3 | 0 |  |  |  |  | S6 | 4.5 |  |  |  | S6 |  |  |  |  |  |  |
|  | Core |  | 4 | 0 |  | 3.7 | 0 |  |  |  |  |  |  |  |  |  |  |  |  |  |
| L7 | GND | 2 oz | 2.6 | 0 |  |  |  |  | P7 | 0 |  |  |  | P7 |  |  |  |  |  |  |
|  | Prepreg |  | 2.7 | 0 |  | 3.5 | 0 |  |  |  |  |  |  |  |  |  |  |  |  |  |
| Bottom | Signal | 0.5 oz+plating | 1.9 | 0 |  |  |  |  | S8 | 4 |  |  |  | S8 | 4 | 9 |  |  |  |  |
|  | Mask |  | 0.5 | 0 |  | 3.8 | 0 |  |  |  |  |  |  |  |  |  |  |  |  |  |
| Thickness requirement: 1.6±10% mm |  | mil | 60.2 |  |  |  |  |  |  |  |  |  |  |  |  |  |  |  |  |  |
|  |  | mm | 1.5290830581661166 |  |  |  |  |  |  |  |  |  |  |  |  |  |  |  |  |  |
| Note: | 1. Unit is mil |  |  |  |  |  |  |  |  |  |  |  |  |  |  |  |  |  |  |  |
|  | 2. The total thickness includes trace and solder mask , not G/F  area |  |  |  |  |  |  |  |  |  |  |  |  |  |  |  |  |  |  |  |
|  | 3. Min hole copper thickness is 1.0 mil |  |  |  |  |  |  |  |  |  |  |  |  |  |  |  |  |  |  |  |
|  | 4. Min surface copper thickness 1.5 mil |  |  |  |  |  |  |  |  |  |  |  |  |  |  |  |  |  |  |  |
